#ISCELL
  mstr_misc dns *
  *
#ISCELL
  pure_quanta quanta_title_block_c *
  *
#ISCELL
  logical_power universal_gnd *
  page253_i1
#ISCELL
  logical_power universal_gnd *
  page253_i10
#CELL
  pure_quanta q_cap *
  page253_i11
#CELL
  pure_quanta q_res *
  page253_i12
#ISCELL
  logical_power vcc15 *
  page253_i13
#ISCELL
  logical_power universal_gnd *
  page253_i14
#CELL
  pure_quanta q_cap *
  page253_i15
#ISCELL
  logical_power universal_gnd *
  page253_i16
#ISCELL
  standard offpage *
  page253_i17
#CELL
  pure_quanta q_res *
  page253_i18
#CELL
  pure_quanta q_cap *
  page253_i19
#CELL
  pure_quanta q_res *
  page253_i2
#CELL
  pure_quanta q_cap *
  page253_i20
#CELL
  pure_quanta q_inductor4p_14 *
  page253_i21
#CELL
  pure_quanta q_cap *
  page253_i22
#CELL
  pure_quanta q_cap *
  page253_i23
#CELL
  pure_quanta q_cap *
  page253_i24
#ISCELL
  logical_power universal_gnd *
  page253_i25
#CELL
  pure_quanta q_res *
  page253_i26
#ISCELL
  logical_power vcc15 *
  page253_i27
#ISCELL
  logical_power universal_gnd *
  page253_i28
#CELL
  pure_quanta q_res *
  page253_i29
#ISCELL
  logical_power universal_gnd *
  page253_i3
#ISCELL
  standard offpage *
  page253_i30
#ISCELL
  standard offpage *
  page253_i31
#ISCELL
  standard offpage *
  page253_i32
#ISCELL
  standard offpage *
  page253_i33
#CELL
  pure_quanta q_cap *
  page253_i34
#ISCELL
  logical_power universal_gnd *
  page253_i35
#CELL
  pure_quanta q_cap *
  page253_i36
#CELL
  pure_quanta q_res *
  page253_i37
#ISCELL
  logical_power universal_gnd *
  page253_i38
#CELL
  pure_quanta q_cap *
  page253_i39
#ISCELL
  standard offpage *
  page253_i4
#CELL
  pure_quanta isl99390frztr5935 *
  page253_i40
#ISCELL
  logical_power vcc15 *
  page253_i41
#CELL
  pure_quanta q_res *
  page253_i42
#ISCELL
  logical_power universal_gnd *
  page253_i43
#CELL
  pure_quanta q_cap *
  page253_i44
#ISCELL
  standard offpage *
  page253_i45
#CELL
  pure_quanta q_inductor4p_14 *
  page253_i46
#CELL
  pure_quanta q_cap *
  page253_i47
#CELL
  pure_quanta q_cap *
  page253_i48
#CELL
  pure_quanta q_cap *
  page253_i49
#ISCELL
  standard offpage *
  page253_i5
#CELL
  pure_quanta q_cap *
  page253_i50
#CELL
  pure_quanta q_res *
  page253_i51
#ISCELL
  standard offpage *
  page253_i52
#ISCELL
  logical_power universal_gnd *
  page253_i53
#CELL
  pure_quanta q_cap *
  page253_i54
#ISCELL
  logical_power vcc15 *
  page253_i55
#CELL
  pure_quanta q_capp *
  page253_i56
#CELL
  pure_quanta q_cap *
  page253_i57
#CELL
  pure_quanta q_cap *
  page253_i58
#CELL
  pure_quanta q_res *
  page253_i59
#CELL
  pure_quanta isl99390frztr5935 *
  page253_i6
#CELL
  pure_quanta q_capp *
  page253_i60
#CELL
  pure_quanta q_capp *
  page253_i61
#CELL
  pure_quanta q_capp *
  page253_i62
#CELL
  pure_quanta q_capp *
  page253_i63
#CELL
  pure_quanta q_capp *
  page253_i64
#ISCELL
  logical_power universal_gnd *
  page253_i65
#CELL
  pure_quanta q_capp *
  page253_i66
#CELL
  pure_quanta q_capp *
  page253_i67
#ISCELL
  logical_power vcc15 *
  page253_i68
#ISCELL
  logical_power universal_gnd *
  page253_i69
#ISCELL
  standard offpage *
  page253_i7
#CELL
  pure_quanta q_capp *
  page253_i70
#ISCELL
  logical_power universal_gnd *
  page253_i71
#ISCELL
  logical_power vcc15 *
  page253_i72
#CELL
  pure_quanta q_res *
  page253_i73
#ISCELL
  logical_power universal_gnd *
  page253_i74
#CELL
  pure_quanta q_cap *
  page253_i75
#ISCELL
  standard offpage *
  page253_i76
#ISCELL
  logical_power gnd *
  page253_i77
#ISCELL
  logical_power vcc15 *
  page253_i78
#ISCELL
  logical_power vcc15 *
  page253_i79
#ISCELL
  standard offpage *
  page253_i8
#CELL
  pure_quanta q_cap *
  page253_i80
#CELL
  pure_quanta q_res *
  page253_i81
#CELL
  pure_quanta q_inductor *
  page253_i82
#CELL
  pure_quanta q_cap *
  page253_i83
#CELL
  pure_quanta q_cap *
  page253_i84
#CELL
  pure_quanta q_cap *
  page253_i85
#CELL
  pure_quanta q_cap *
  page253_i86
#ISCELL
  logical_power universal_gnd *
  page253_i87
#ISCELL
  logical_power vcc15 *
  page253_i88
#ISCELL
  logical_power vcc15 *
  page253_i89
#CELL
  pure_quanta q_cap *
  page253_i9
#ISCELL
  logical_power universal_gnd *
  page253_i90
#CELL
  pure_quanta q_capp *
  page253_i91
#CELL
  pure_quanta q_capp *
  page253_i92
#CELL
  pure_quanta q_capp *
  page253_i93
#CELL
  pure_quanta q_capp *
  page253_i94
#CELL
  pure_quanta q_capp *
  page253_i95
#ISCELL
  logical_power vcc15 *
  page253_i96
#CELL
  pure_quanta q_res *
  page253_i97
